FILE_TYPE = CONNECTIVITY;
{Allegro Design Entry HDL 17.4-2019 S026 (4007227) 1/17/2022}
"PAGE_NUMBER" = 318;
0"NC";
1"P5E_CPU1_P2_TX_BUF_C_DP<0>";
2"P5E_CPU1_P3_RX_BUF_DP<0>";
3"P5E_CPU1_P3_RX_BUF_DN<0>";
4"P5E_CPU1_P3_TX_BUF_C_DN<0>";
5"P5E_CPU1_P2_TX_BUF_C_DN<0>";
6"GND\g";
7"P5E_CPU1_P2_RX_BUF_DP<0>";
8"GPU_FPGA_BOOT_EN_BUF";
9"GPU_FPGA_EROT_RECOV_BUF_N";
10"P5E_CPU1_P3_TX_BUF_C_DN<1>";
11"P5E_CPU1_P3_TX_BUF_C_DP<1>";
12"P5E_CPU1_P2_TX_BUF_C_DP<1>";
13"P5E_CPU1_P2_TX_BUF_C_DN<1>";
14"P5E_CPU1_P3_RX_BUF_DP<1>";
15"P5E_CPU1_P3_RX_BUF_DN<1>";
16"P5E_CPU1_P2_RX_BUF_DP<1>";
17"P5E_CPU1_P2_RX_BUF_DN<1>";
18"P5E_CPU1_P3_TX_BUF_C_DP<2>";
19"P5E_CPU1_P3_TX_BUF_C_DN<2>";
20"P5E_CPU1_P2_TX_BUF_C_DP<2>";
21"P5E_CPU1_P2_TX_BUF_C_DN<2>";
22"P5E_CPU1_P3_RX_BUF_DP<2>";
23"P5E_CPU1_P3_RX_BUF_DN<2>";
24"FM_SMB_1_ALERT_GPU_N";
25"GPU_HMC_PRSNT_N";
26"P5E_CPU1_P3_TX_BUF_C_DP<3>";
27"P5E_CPU1_P3_TX_BUF_C_DN<3>";
28"P5E_CPU1_P2_TX_BUF_C_DP<3>";
29"P5E_CPU1_P2_TX_BUF_C_DN<3>";
30"P5E_CPU1_P3_RX_BUF_DP<3>";
31"P5E_CPU1_P3_RX_BUF_DN<3>";
32"P5E_CPU1_P2_TX_BUF_C_DN<4>";
33"GND\g";
34"P5E_CPU1_P2_TX_BUF_C_DP<4>";
35"P5E_CPU1_P3_RX_BUF_DP<4>";
36"P5E_CPU1_P2_RX_BUF_DP<4>";
37"P5E_CPU1_P2_RX_BUF_DN<4>";
38"GPU_BASE_HMC_READY";
39"FM_SMB_2_ALERT_GPU_N";
40"P5E_CPU1_P3_TX_BUF_C_DP<5>";
41"P5E_CPU1_P2_TX_BUF_C_DP<5>";
42"P5E_CPU1_P3_RX_BUF_DP<5>";
43"P5E_CPU1_P3_RX_BUF_DN<5>";
44"P5E_CPU1_P2_RX_BUF_DP<5>";
45"P5E_CPU1_P2_RX_BUF_DN<5>";
46"P5E_CPU1_P3_TX_BUF_C_DP<6>";
47"P5E_CPU1_P3_TX_BUF_C_DN<6>";
48"P5E_CPU1_P2_TX_BUF_C_DP<6>";
49"P5E_CPU1_P2_TX_BUF_C_DN<6>";
50"P5E_CPU1_P3_RX_BUF_DP<6>";
51"P5E_CPU1_P3_RX_BUF_DN<6>";
52"P5E_CPU1_P2_RX_BUF_DP<6>";
53"P5E_CPU1_P2_RX_BUF_DN<6>";
54"GPU_BASE_STBY_EN_BUF";
55"GPU_FPGA_EROT_RST_BUF_N";
56"P5E_CPU1_P3_TX_BUF_C_DP<7>";
57"P5E_CPU1_P3_TX_BUF_C_DN<7>";
58"P5E_CPU1_P3_TX_BUF_C_DN<4>";
59"P5E_CPU1_P3_TX_BUF_C_DP<4>";
60"P5E_CPU1_P3_RX_BUF_DN<4>";
61"P5E_CPU1_P3_TX_BUF_C_DN<5>";
62"P5E_CPU1_P2_TX_BUF_C_DN<5>";
63"P5E_CPU1_P2_TX_BUF_C_DP<7>";
64"P5E_CPU1_P3_RX_BUF_DN<7>";
65"P5E_CPU1_P3_RX_BUF_DP<7>";
66"P5E_CPU1_P2_TX_BUF_C_DN<7>";
67"P5E_CPU1_P2_RX_BUF_DN<0>";
68"P5E_CPU1_P3_TX_BUF_C_DP<0>";
69"P5E_CPU1_P2_RX_BUF_DN<2>";
70"P5E_CPU1_P2_RX_BUF_DN<3>";
71"P5E_CPU1_P2_RX_BUF_DP<3>";
72"P5E_CPU1_P2_RX_BUF_DN<7>";
73"P5E_CPU1_P2_RX_BUF_DP<2>";
74"P5E_CPU1_P2_RX_BUF_DP<7>";
%"UNIVERSAL_GND"
"1","(-2150,-1700)","0","pure_quanta_power","I15";
;
CDS_LIB"pure_quanta_power"
HDL_POWER"GND";
"A"33;
%"CONN112_10137002101LF"
"1","(-1050,200)","0","pure_quanta","I16";
;
LOCATION"J110"
$SEC"1"
CDS_SEC"1"
MATERIAL"IO"
PART_TYPE"THLF"
CDS_LIB"pure_quanta"
NEEDS_NO_SIZE"TRUE"
CDS_LMAN_SYM_OUTLINE"-775,1650,775,-1650"
VALUE"CONN112_10137002-101LF"
PART_NUMBER"DFHSB2FR012";
"N8"
$PN"N8"55;
"M8"
$PN"M8"33;
"N7"
$PN"N7"33;
"M7"
$PN"M7"46;
"N6"
$PN"N6"39;
"M6"
$PN"M6"33;
"N5"
$PN"N5"33;
"M5"
$PN"M5"59;
"L5"
$PN"L5"58;
"L6"
$PN"L6"40;
"L7"
$PN"L7"47;
"L8"
$PN"L8"56;
"K5"
$PN"K5"33;
"K6"
$PN"K6"61;
"K7"
$PN"K7"33;
"K8"
$PN"K8"57;
"J5"
$PN"J5"34;
"J6"
$PN"J6"33;
"J7"
$PN"J7"48;
"J8"
$PN"J8"33;
"I5"
$PN"I5"32;
"I6"
$PN"I6"41;
"I7"
$PN"I7"49;
"I8"
$PN"I8"63;
"H5"
$PN"H5"33;
"H6"
$PN"H6"62;
"H7"
$PN"H7"33;
"H8"
$PN"H8"66;
"G5"
$PN"G5"35;
"G6"
$PN"G6"33;
"G7"
$PN"G7"50;
"G8"
$PN"G8"33;
"F5"
$PN"F5"60;
"F6"
$PN"F6"42;
"F7"
$PN"F7"51;
"F8"
$PN"F8"65;
"E5"
$PN"E5"33;
"E6"
$PN"E6"43;
"E7"
$PN"E7"33;
"E8"
$PN"E8"64;
"D5"
$PN"D5"36;
"D6"
$PN"D6"33;
"D7"
$PN"D7"52;
"D8"
$PN"D8"33;
"C5"
$PN"C5"37;
"C6"
$PN"C6"44;
"C7"
$PN"C7"53;
"C8"
$PN"C8"74;
"B5"
$PN"B5"33;
"B6"
$PN"B6"45;
"B7"
$PN"B7"33;
"B8"
$PN"B8"72;
"A5"
$PN"A5"38;
"A6"
$PN"A6"33;
"A7"
$PN"A7"54;
"A8"
$PN"A8"33;
%"UNIVERSAL_GND"
"1","(2575,-1700)","0","pure_quanta_power","I53";
;
CDS_LIB"pure_quanta_power"
HDL_POWER"GND";
"A"6;
%"CONN112_10137002101LF"
"2","(3725,250)","0","pure_quanta","I76";
;
LOCATION"J110"
$SEC"2"
CDS_SEC"2"
PART_TYPE"THLF"
MATERIAL"IO"
CDS_LMAN_SYM_OUTLINE"-775,1650,775,-1650"
NEEDS_NO_SIZE"TRUE"
CDS_LIB"pure_quanta"
VALUE"CONN112_10137002-101LF"
PART_NUMBER"DFHSB2FR012";
"N4"
$PN"N4"24;
"M4"
$PN"M4"6;
"N3"
$PN"N3"6;
"M3"
$PN"M3"18;
"N2"
$PN"N2"8;
"M2"
$PN"M2"6;
"N1"
$PN"N1"6;
"M1"
$PN"M1"68;
"L1"
$PN"L1"4;
"L2"
$PN"L2"11;
"L3"
$PN"L3"19;
"L4"
$PN"L4"26;
"K1"
$PN"K1"6;
"K2"
$PN"K2"10;
"K3"
$PN"K3"6;
"K4"
$PN"K4"27;
"J1"
$PN"J1"1;
"J2"
$PN"J2"6;
"J3"
$PN"J3"20;
"J4"
$PN"J4"6;
"I1"
$PN"I1"5;
"I2"
$PN"I2"12;
"I3"
$PN"I3"21;
"I4"
$PN"I4"28;
"H1"
$PN"H1"6;
"H2"
$PN"H2"13;
"H3"
$PN"H3"6;
"H4"
$PN"H4"29;
"G1"
$PN"G1"2;
"G2"
$PN"G2"6;
"G3"
$PN"G3"22;
"G4"
$PN"G4"6;
"F1"
$PN"F1"3;
"F2"
$PN"F2"14;
"F3"
$PN"F3"23;
"F4"
$PN"F4"30;
"E1"
$PN"E1"6;
"E2"
$PN"E2"15;
"E3"
$PN"E3"6;
"E4"
$PN"E4"31;
"D1"
$PN"D1"7;
"D2"
$PN"D2"6;
"D3"
$PN"D3"73;
"D4"
$PN"D4"6;
"C1"
$PN"C1"67;
"C2"
$PN"C2"16;
"C3"
$PN"C3"69;
"C4"
$PN"C4"71;
"B1"
$PN"B1"6;
"B2"
$PN"B2"17;
"B3"
$PN"B3"6;
"B4"
$PN"B4"70;
"A1"
$PN"A1"9;
"A2"
$PN"A2"6;
"A3"
$PN"A3"25;
"A4"
$PN"A4"6;
END.
